(kicad_pcb
	(version 20260206)
	(generator "pcbnew")
	(generator_version "10.0")
	(general
		(thickness 1.6)
		(legacy_teardrops no)
	)
	(paper "A4")
	(title_block
		(title "Wiwynn_Tioga_Pass_MB.brd")
		(comment 1 "Tioga Pass / footprints 4017-4023 of 4770")
	)
	(layers
		(0 "F.Cu" signal "TOP")
		(4 "In1.Cu" signal "L2GND")
		(6 "In2.Cu" signal "L3")
		(8 "In3.Cu" signal "L4GND")
		(10 "In4.Cu" signal "L5")
		(12 "In5.Cu" signal "L6GND")
		(14 "In6.Cu" signal "L7VCC")
		(16 "In7.Cu" signal "L8VCC")
		(18 "In8.Cu" signal "L9GND")
		(20 "In9.Cu" signal "L10")
		(22 "In10.Cu" signal "L11GND")
		(24 "In11.Cu" signal "L12")
		(26 "In12.Cu" signal "L13GND")
		(2 "B.Cu" signal "BOTTOM")
		(9 "F.Adhes" user "F.Adhesive")
		(11 "B.Adhes" user "B.Adhesive")
		(13 "F.Paste" user "Package Geometry/Pastemask Top")
		(15 "B.Paste" user "Package Geometry/Pastemask Bottom")
		(5 "F.SilkS" user "Ref Des/Silkscreen Top")
		(7 "B.SilkS" user "Ref Des/Silkscreen Bottom")
		(1 "F.Mask" user "Board Geometry/Soldermask Top")
		(3 "B.Mask" user "Board Geometry/Soldermask Bottom")
		(17 "Dwgs.User" user "User.Drawings")
		(19 "Cmts.User" user "User.Comments")
		(21 "Eco1.User" user "User.Eco1")
		(23 "Eco2.User" user "User.Eco2")
		(25 "Edge.Cuts" user "Board Geometry/Outline")
		(27 "Margin" user)
		(31 "F.CrtYd" user "Package Geometry/Place Bound Top")
		(29 "B.CrtYd" user "Package Geometry/Place Bound Bottom")
		(35 "F.Fab" user "Ref Des/Assembly Top")
		(33 "B.Fab" user "Ref Des/Assembly Bottom")
	)
	(footprint ""
		(layer "B.Cu")
		(at 385.813808 -84.729828 180)
		(property "Reference" "R7D44"
			(at 0.8382 -0.67818 180)
			(unlocked yes)
			(layer "B.SilkS")
			(effects
				(font
					(size 0.4064 0.254)
					(thickness 0.1524)
				)
				(justify left mirror)
			)
		)
		(property "Value" ""
			(at 0 0 0)
			(layer "B.Fab")
			(effects
				(font
					(size 1.27 1.27)
				)
				(justify mirror)
			)
		)
		(duplicate_pad_numbers_are_jumpers no)
		(fp_poly
			(pts
				(xy 0.2794 -0.1016) (xy -0.2794 -0.1016) (xy -0.2794 0.9906) (xy 0.2794 0.9906)
			)
			(stroke
				(width 0)
				(type default)
			)
			(fill no)
			(layer "B.CrtYd")
		)
		(fp_line
			(start 0.2794 0.9906)
			(end -0.2794 0.9906)
			(stroke
				(width 0.1)
				(type default)
			)
			(layer "B.Fab")
		)
		(fp_line
			(start 0.2794 -0.1016)
			(end 0.2794 0.9906)
			(stroke
				(width 0.1)
				(type default)
			)
			(layer "B.Fab")
		)
		(fp_line
			(start -0.2794 0.9906)
			(end -0.2794 -0.1016)
			(stroke
				(width 0.1)
				(type default)
			)
			(layer "B.Fab")
		)
		(fp_line
			(start -0.2794 -0.1016)
			(end 0.2794 -0.1016)
			(stroke
				(width 0.1)
				(type default)
			)
			(layer "B.Fab")
		)
		(pad "1" smd rect
			(at 0 0)
			(size 0.508 0.508)
			(layers "B.Cu" "B.Mask" "B.Paste")
			(net "P1V05_PCH_STBY")
		)
		(pad "2" smd rect
			(at 0 0.889)
			(size 0.508 0.508)
			(layers "B.Cu" "B.Mask" "B.Paste")
			(net "FM_OCP_MEZZB_PRES_1V05_PCH_N")
		)
		(zone
			(layer "B.Cu")
			(hatch none 0.5)
			(connect_pads
				(clearance 0)
			)
			(min_thickness 0.25)
			(keepout
				(tracks not_allowed)
				(vias allowed)
				(pads allowed)
				(copperpour not_allowed)
				(footprints allowed)
			)
			(placement
				(enabled no)
				(sheetname "")
			)
			(fill
				(thermal_gap 0.5)
				(thermal_bridge_width 0.5)
				(island_removal_mode 0)
			)
			(polygon
				(pts
					(xy 385.559808 -85.364828) (xy 386.067808 -85.364828) (xy 386.067808 -84.983828) (xy 385.559808 -84.983828)
				)
			)
		)
		(zone
			(layer "B.Cu")
			(hatch none 0.5)
			(connect_pads
				(clearance 0)
			)
			(min_thickness 0.25)
			(keepout
				(tracks allowed)
				(vias not_allowed)
				(pads allowed)
				(copperpour not_allowed)
				(footprints allowed)
			)
			(placement
				(enabled no)
				(sheetname "")
			)
			(fill
				(thermal_gap 0.5)
				(thermal_bridge_width 0.5)
				(island_removal_mode 0)
			)
			(polygon
				(pts
					(xy 385.559808 -84.983828) (xy 386.067808 -84.983828) (xy 386.067808 -85.364828) (xy 385.559808 -85.364828)
				)
			)
		)
	)
	(footprint ""
		(layer "B.Cu")
		(at 198.623428 -69.477382 90)
		(property "Reference" "C4D14"
			(at 0 0 90)
			(layer "B.SilkS")
			(hide yes)
			(effects
				(font
					(size 1.27 1.27)
				)
				(justify mirror)
			)
		)
		(property "Value" "*"
			(at -1.1811 -2.8194 90)
			(unlocked yes)
			(layer "B.Fab")
			(hide yes)
			(effects
				(font
					(size 1.27 1.016)
					(thickness 0.1524)
				)
				(justify mirror)
			)
		)
		(property "Device Type" "SC1U10V2KX-4-GP_SMD-BCG6-SC1U1A"
			(at -1.1811 -4.3434 90)
			(unlocked yes)
			(layer "B.Fab")
			(hide yes)
			(effects
				(font
					(size 1.27 1.016)
					(thickness 0.1524)
				)
				(justify mirror)
			)
		)
		(duplicate_pad_numbers_are_jumpers no)
		(fp_rect
			(start 0.4318 0.9525)
			(end -0.4318 -0.9525)
			(stroke
				(width 0)
				(type default)
			)
			(fill no)
			(layer "B.CrtYd")
		)
		(fp_rect
			(start 0.4318 0.9525)
			(end -0.4318 -0.9525)
			(stroke
				(width 0)
				(type default)
			)
			(fill no)
			(layer "B.Fab")
		)
		(pad "1" smd custom
			(at 0 -0.4445 270)
			(size 0.1524 0.1524)
			(layers "B.Cu" "B.Mask" "B.Paste")
			(net "P5V_STBY")
			(options
				(clearance outline)
				(anchor circle)
			)
			(primitives
				(gr_poly
					(pts
						(arc
							(start 0.3048 0.2032)
							(mid 0.275042 0.275042)
							(end 0.2032 0.3048)
						)
						(arc
							(start -0.2032 0.3048)
							(mid -0.275042 0.275042)
							(end -0.3048 0.2032)
						)
						(arc
							(start -0.3048 -0.2032)
							(mid -0.275042 -0.275042)
							(end -0.2032 -0.3048)
						)
						(arc
							(start 0.2032 -0.3048)
							(mid 0.275042 -0.275042)
							(end 0.3048 -0.2032)
						)
					)
					(width 0)
					(fill yes)
				)
			)
		)
		(pad "2" smd custom
			(at 0 0.4445 270)
			(size 0.1524 0.1524)
			(layers "B.Cu" "B.Mask" "B.Paste")
			(net "GND")
			(options
				(clearance outline)
				(anchor circle)
			)
			(primitives
				(gr_poly
					(pts
						(arc
							(start 0.3048 0.2032)
							(mid 0.275042 0.275042)
							(end 0.2032 0.3048)
						)
						(arc
							(start -0.2032 0.3048)
							(mid -0.275042 0.275042)
							(end -0.3048 0.2032)
						)
						(arc
							(start -0.3048 -0.2032)
							(mid -0.275042 -0.275042)
							(end -0.2032 -0.3048)
						)
						(arc
							(start 0.2032 -0.3048)
							(mid 0.275042 -0.275042)
							(end 0.3048 -0.2032)
						)
					)
					(width 0)
					(fill yes)
				)
			)
		)
	)
	(footprint ""
		(layer "B.Cu")
		(at 258.2037 -144.8816 -90)
		(property "Reference" "C5L15"
			(at 0 0 90)
			(layer "B.SilkS")
			(hide yes)
			(effects
				(font
					(size 1.27 1.27)
				)
				(justify mirror)
			)
		)
		(property "Value" ""
			(at 0 0 90)
			(layer "B.Fab")
			(effects
				(font
					(size 1.27 1.27)
				)
				(justify mirror)
			)
		)
		(duplicate_pad_numbers_are_jumpers no)
		(fp_rect
			(start 0.500126 1.598422)
			(end -0.500126 -0.201422)
			(stroke
				(width 0)
				(type default)
			)
			(fill no)
			(layer "B.CrtYd")
		)
		(fp_line
			(start -0.500126 1.598422)
			(end 0.500126 1.598422)
			(stroke
				(width 0.1)
				(type default)
			)
			(layer "B.Fab")
		)
		(fp_line
			(start 0.500126 1.598422)
			(end 0.500126 -0.201422)
			(stroke
				(width 0.1)
				(type default)
			)
			(layer "B.Fab")
		)
		(fp_line
			(start -0.500126 -0.201422)
			(end -0.500126 1.598422)
			(stroke
				(width 0.1)
				(type default)
			)
			(layer "B.Fab")
		)
		(fp_line
			(start 0.500126 -0.201422)
			(end -0.500126 -0.201422)
			(stroke
				(width 0.1)
				(type default)
			)
			(layer "B.Fab")
		)
		(pad "1" smd rect
			(at 0 0 180)
			(size 0.889 0.9906)
			(layers "B.Cu" "B.Mask" "B.Paste")
			(net "PVDDQ_DEF")
		)
		(pad "2" smd rect
			(at 0 1.397 180)
			(size 0.889 0.9906)
			(layers "B.Cu" "B.Mask" "B.Paste")
			(net "GND")
		)
		(zone
			(layer "B.Cu")
			(hatch none 0.5)
			(connect_pads
				(clearance 0)
			)
			(min_thickness 0.25)
			(keepout
				(tracks allowed)
				(vias not_allowed)
				(pads allowed)
				(copperpour not_allowed)
				(footprints allowed)
			)
			(placement
				(enabled no)
				(sheetname "")
			)
			(fill
				(thermal_gap 0.5)
				(thermal_bridge_width 0.5)
				(island_removal_mode 0)
			)
			(polygon
				(pts
					(xy 257.2512 -144.3863) (xy 257.7592 -144.3863) (xy 257.7592 -145.3769) (xy 257.2512 -145.3769)
				)
			)
		)
		(zone
			(layer "B.Cu")
			(hatch none 0.5)
			(connect_pads
				(clearance 0)
			)
			(min_thickness 0.25)
			(keepout
				(tracks not_allowed)
				(vias allowed)
				(pads allowed)
				(copperpour not_allowed)
				(footprints allowed)
			)
			(placement
				(enabled no)
				(sheetname "")
			)
			(fill
				(thermal_gap 0.5)
				(thermal_bridge_width 0.5)
				(island_removal_mode 0)
			)
			(polygon
				(pts
					(xy 257.2512 -144.3863) (xy 257.7592 -144.3863) (xy 257.7592 -145.3769) (xy 257.2512 -145.3769)
				)
			)
		)
	)
	(footprint ""
		(layer "B.Cu")
		(at 439.293 -52.3875)
		(property "Reference" "C2R15"
			(at 0 0 0)
			(layer "B.SilkS")
			(hide yes)
			(effects
				(font
					(size 1.27 1.27)
				)
				(justify mirror)
			)
		)
		(property "Value" ""
			(at 0 0 0)
			(layer "B.Fab")
			(effects
				(font
					(size 1.27 1.27)
				)
				(justify mirror)
			)
		)
		(duplicate_pad_numbers_are_jumpers no)
		(fp_poly
			(pts
				(xy -0.3048 -0.1016) (xy -0.3048 0.9906) (xy 0.3048 0.9906) (xy 0.3048 -0.1016)
			)
			(stroke
				(width 0)
				(type default)
			)
			(fill no)
			(layer "B.CrtYd")
		)
		(fp_line
			(start -0.3048 -0.1016)
			(end 0.3048 -0.1016)
			(stroke
				(width 0.1)
				(type default)
			)
			(layer "B.Fab")
		)
		(fp_line
			(start -0.3048 0.9906)
			(end -0.3048 -0.1016)
			(stroke
				(width 0.1)
				(type default)
			)
			(layer "B.Fab")
		)
		(fp_line
			(start 0.3048 -0.1016)
			(end 0.3048 0.9906)
			(stroke
				(width 0.1)
				(type default)
			)
			(layer "B.Fab")
		)
		(fp_line
			(start 0.3048 0.9906)
			(end -0.3048 0.9906)
			(stroke
				(width 0.1)
				(type default)
			)
			(layer "B.Fab")
		)
		(pad "1" smd rect
			(at 0 0 180)
			(size 0.508 0.508)
			(layers "B.Cu" "B.Mask" "B.Paste")
			(net "P12V_STBY")
		)
		(pad "2" smd rect
			(at 0 0.889 180)
			(size 0.508 0.508)
			(layers "B.Cu" "B.Mask" "B.Paste")
			(net "GND")
		)
		(zone
			(layer "B.Cu")
			(hatch none 0.5)
			(connect_pads
				(clearance 0)
			)
			(min_thickness 0.25)
			(keepout
				(tracks allowed)
				(vias not_allowed)
				(pads allowed)
				(copperpour not_allowed)
				(footprints allowed)
			)
			(placement
				(enabled no)
				(sheetname "")
			)
			(fill
				(thermal_gap 0.5)
				(thermal_bridge_width 0.5)
				(island_removal_mode 0)
			)
			(polygon
				(pts
					(xy 439.547 -52.1335) (xy 439.039 -52.1335) (xy 439.039 -51.7525) (xy 439.547 -51.7525)
				)
			)
		)
		(zone
			(layer "B.Cu")
			(hatch none 0.5)
			(connect_pads
				(clearance 0)
			)
			(min_thickness 0.25)
			(keepout
				(tracks not_allowed)
				(vias allowed)
				(pads allowed)
				(copperpour not_allowed)
				(footprints allowed)
			)
			(placement
				(enabled no)
				(sheetname "")
			)
			(fill
				(thermal_gap 0.5)
				(thermal_bridge_width 0.5)
				(island_removal_mode 0)
			)
			(polygon
				(pts
					(xy 439.547 -51.7525) (xy 439.039 -51.7525) (xy 439.039 -52.1335) (xy 439.547 -52.1335)
				)
			)
		)
	)
	(footprint ""
		(layer "B.Cu")
		(at 421.956992 -77.523594 180)
		(property "Reference" "R1R8"
			(at 0 0 0)
			(layer "B.SilkS")
			(hide yes)
			(effects
				(font
					(size 1.27 1.27)
				)
				(justify mirror)
			)
		)
		(property "Value" ""
			(at 0 0 0)
			(layer "B.Fab")
			(effects
				(font
					(size 1.27 1.27)
				)
				(justify mirror)
			)
		)
		(duplicate_pad_numbers_are_jumpers no)
		(fp_poly
			(pts
				(xy 0.2794 -0.1016) (xy -0.2794 -0.1016) (xy -0.2794 0.9906) (xy 0.2794 0.9906)
			)
			(stroke
				(width 0)
				(type default)
			)
			(fill no)
			(layer "B.CrtYd")
		)
		(fp_line
			(start 0.2794 0.9906)
			(end -0.2794 0.9906)
			(stroke
				(width 0.1)
				(type default)
			)
			(layer "B.Fab")
		)
		(fp_line
			(start 0.2794 -0.1016)
			(end 0.2794 0.9906)
			(stroke
				(width 0.1)
				(type default)
			)
			(layer "B.Fab")
		)
		(fp_line
			(start -0.2794 0.9906)
			(end -0.2794 -0.1016)
			(stroke
				(width 0.1)
				(type default)
			)
			(layer "B.Fab")
		)
		(fp_line
			(start -0.2794 -0.1016)
			(end 0.2794 -0.1016)
			(stroke
				(width 0.1)
				(type default)
			)
			(layer "B.Fab")
		)
		(pad "1" smd rect
			(at 0 0)
			(size 0.508 0.508)
			(layers "B.Cu" "B.Mask" "B.Paste")
			(net "FM_THROTTLE_R1_N")
		)
		(pad "2" smd rect
			(at 0 0.889)
			(size 0.508 0.508)
			(layers "B.Cu" "B.Mask" "B.Paste")
			(net "FM_THROTTLE_N")
		)
		(zone
			(layer "B.Cu")
			(hatch none 0.5)
			(connect_pads
				(clearance 0)
			)
			(min_thickness 0.25)
			(keepout
				(tracks not_allowed)
				(vias allowed)
				(pads allowed)
				(copperpour not_allowed)
				(footprints allowed)
			)
			(placement
				(enabled no)
				(sheetname "")
			)
			(fill
				(thermal_gap 0.5)
				(thermal_bridge_width 0.5)
				(island_removal_mode 0)
			)
			(polygon
				(pts
					(xy 421.702992 -78.158594) (xy 422.210992 -78.158594) (xy 422.210992 -77.777594) (xy 421.702992 -77.777594)
				)
			)
		)
		(zone
			(layer "B.Cu")
			(hatch none 0.5)
			(connect_pads
				(clearance 0)
			)
			(min_thickness 0.25)
			(keepout
				(tracks allowed)
				(vias not_allowed)
				(pads allowed)
				(copperpour not_allowed)
				(footprints allowed)
			)
			(placement
				(enabled no)
				(sheetname "")
			)
			(fill
				(thermal_gap 0.5)
				(thermal_bridge_width 0.5)
				(island_removal_mode 0)
			)
			(polygon
				(pts
					(xy 421.702992 -77.777594) (xy 422.210992 -77.777594) (xy 422.210992 -78.158594) (xy 421.702992 -78.158594)
				)
			)
		)
	)
	(footprint ""
		(layer "B.Cu")
		(at 477.081088 -132.83311)
		(property "Reference" "R1W38"
			(at 0.8382 -0.67818 0)
			(unlocked yes)
			(layer "B.SilkS")
			(effects
				(font
					(size 0.4064 0.254)
					(thickness 0.1524)
				)
				(justify left mirror)
			)
		)
		(property "Value" ""
			(at 0 0 0)
			(layer "B.Fab")
			(effects
				(font
					(size 1.27 1.27)
				)
				(justify mirror)
			)
		)
		(duplicate_pad_numbers_are_jumpers no)
		(fp_poly
			(pts
				(xy 0.2794 -0.1016) (xy -0.2794 -0.1016) (xy -0.2794 0.9906) (xy 0.2794 0.9906)
			)
			(stroke
				(width 0)
				(type default)
			)
			(fill no)
			(layer "B.CrtYd")
		)
		(fp_line
			(start -0.2794 -0.1016)
			(end 0.2794 -0.1016)
			(stroke
				(width 0.1)
				(type default)
			)
			(layer "B.Fab")
		)
		(fp_line
			(start -0.2794 0.9906)
			(end -0.2794 -0.1016)
			(stroke
				(width 0.1)
				(type default)
			)
			(layer "B.Fab")
		)
		(fp_line
			(start 0.2794 -0.1016)
			(end 0.2794 0.9906)
			(stroke
				(width 0.1)
				(type default)
			)
			(layer "B.Fab")
		)
		(fp_line
			(start 0.2794 0.9906)
			(end -0.2794 0.9906)
			(stroke
				(width 0.1)
				(type default)
			)
			(layer "B.Fab")
		)
		(pad "1" smd rect
			(at 0 0 180)
			(size 0.508 0.508)
			(layers "B.Cu" "B.Mask" "B.Paste")
			(net "SMB_DEBUG_STBY_LVC3_SCL_CONN")
		)
		(pad "2" smd rect
			(at 0 0.889 180)
			(size 0.508 0.508)
			(layers "B.Cu" "B.Mask" "B.Paste")
			(net "SMB_DEBUG_STBY_LVC3_SCL_R1")
		)
		(zone
			(layer "B.Cu")
			(hatch none 0.5)
			(connect_pads
				(clearance 0)
			)
			(min_thickness 0.25)
			(keepout
				(tracks allowed)
				(vias not_allowed)
				(pads allowed)
				(copperpour not_allowed)
				(footprints allowed)
			)
			(placement
				(enabled no)
				(sheetname "")
			)
			(fill
				(thermal_gap 0.5)
				(thermal_bridge_width 0.5)
				(island_removal_mode 0)
			)
			(polygon
				(pts
					(xy 477.335088 -132.57911) (xy 476.827088 -132.57911) (xy 476.827088 -132.19811) (xy 477.335088 -132.19811)
				)
			)
		)
		(zone
			(layer "B.Cu")
			(hatch none 0.5)
			(connect_pads
				(clearance 0)
			)
			(min_thickness 0.25)
			(keepout
				(tracks not_allowed)
				(vias allowed)
				(pads allowed)
				(copperpour not_allowed)
				(footprints allowed)
			)
			(placement
				(enabled no)
				(sheetname "")
			)
			(fill
				(thermal_gap 0.5)
				(thermal_bridge_width 0.5)
				(island_removal_mode 0)
			)
			(polygon
				(pts
					(xy 477.335088 -132.19811) (xy 476.827088 -132.19811) (xy 476.827088 -132.57911) (xy 477.335088 -132.57911)
				)
			)
		)
	)
	(footprint ""
		(layer "B.Cu")
		(at 365.506 -77.5716 -90)
		(property "Reference" "R7D36"
			(at 0 0 90)
			(layer "B.SilkS")
			(hide yes)
			(effects
				(font
					(size 1.27 1.27)
				)
				(justify mirror)
			)
		)
		(property "Value" ""
			(at 0 0 90)
			(layer "B.Fab")
			(effects
				(font
					(size 1.27 1.27)
				)
				(justify mirror)
			)
		)
		(duplicate_pad_numbers_are_jumpers no)
		(fp_poly
			(pts
				(xy 0.2794 -0.1016) (xy -0.2794 -0.1016) (xy -0.2794 0.9906) (xy 0.2794 0.9906)
			)
			(stroke
				(width 0)
				(type default)
			)
			(fill no)
			(layer "B.CrtYd")
		)
		(fp_line
			(start -0.2794 0.9906)
			(end -0.2794 -0.1016)
			(stroke
				(width 0.1)
				(type default)
			)
			(layer "B.Fab")
		)
		(fp_line
			(start 0.2794 0.9906)
			(end -0.2794 0.9906)
			(stroke
				(width 0.1)
				(type default)
			)
			(layer "B.Fab")
		)
		(fp_line
			(start -0.2794 -0.1016)
			(end 0.2794 -0.1016)
			(stroke
				(width 0.1)
				(type default)
			)
			(layer "B.Fab")
		)
		(fp_line
			(start 0.2794 -0.1016)
			(end 0.2794 0.9906)
			(stroke
				(width 0.1)
				(type default)
			)
			(layer "B.Fab")
		)
		(pad "1" smd rect
			(at 0 0 90)
			(size 0.508 0.508)
			(layers "B.Cu" "B.Mask" "B.Paste")
			(net "FM_156M_CPU1_BRD_OSC_EN")
		)
		(pad "2" smd rect
			(at 0 0.889 90)
			(size 0.508 0.508)
			(layers "B.Cu" "B.Mask" "B.Paste")
			(net "FM_CPU1_STL_BRD_OSC_EN")
		)
		(zone
			(layer "B.Cu")
			(hatch none 0.5)
			(connect_pads
				(clearance 0)
			)
			(min_thickness 0.25)
			(keepout
				(tracks not_allowed)
				(vias allowed)
				(pads allowed)
				(copperpour not_allowed)
				(footprints allowed)
			)
			(placement
				(enabled no)
				(sheetname "")
			)
			(fill
				(thermal_gap 0.5)
				(thermal_bridge_width 0.5)
				(island_removal_mode 0)
			)
			(polygon
				(pts
					(xy 364.871 -77.3176) (xy 364.871 -77.8256) (xy 365.252 -77.8256) (xy 365.252 -77.3176)
				)
			)
		)
		(zone
			(layer "B.Cu")
			(hatch none 0.5)
			(connect_pads
				(clearance 0)
			)
			(min_thickness 0.25)
			(keepout
				(tracks allowed)
				(vias not_allowed)
				(pads allowed)
				(copperpour not_allowed)
				(footprints allowed)
			)
			(placement
				(enabled no)
				(sheetname "")
			)
			(fill
				(thermal_gap 0.5)
				(thermal_bridge_width 0.5)
				(island_removal_mode 0)
			)
			(polygon
				(pts
					(xy 365.252 -77.3176) (xy 365.252 -77.8256) (xy 364.871 -77.8256) (xy 364.871 -77.3176)
				)
			)
		)
	)
)
